(kicad_pcb
	(version 20260206)
	(generator "pcbnew")
	(generator_version "10.0")
	(general
		(thickness 1.6)
		(legacy_teardrops no)
	)
	(paper "A4")
	(title_block
		(title "04192023_DAF0TMB3IC0_F0TG_MB_C_brd_V02_OCP.brd")
		(comment 1 "Grand Teton / footprints 7081-7087 of 8354")
	)
	(layers
		(0 "F.Cu" signal "TOP")
		(4 "In1.Cu" signal "GND")
		(6 "In2.Cu" signal "IN1")
		(8 "In3.Cu" signal "GND1")
		(10 "In4.Cu" signal "IN2")
		(12 "In5.Cu" signal "GND2")
		(14 "In6.Cu" signal "IN3")
		(16 "In7.Cu" signal "GND3")
		(18 "In8.Cu" signal "VCC")
		(20 "In9.Cu" signal "VCC1")
		(22 "In10.Cu" signal "GND4")
		(24 "In11.Cu" signal "IN4")
		(26 "In12.Cu" signal "GND5")
		(28 "In13.Cu" signal "IN5")
		(30 "In14.Cu" signal "GND6")
		(32 "In15.Cu" signal "IN6")
		(34 "In16.Cu" signal "GND7")
		(2 "B.Cu" signal "BOTTOM")
		(9 "F.Adhes" user "F.Adhesive")
		(11 "B.Adhes" user "B.Adhesive")
		(13 "F.Paste" user "Package Geometry/Pastemask Top")
		(15 "B.Paste" user "Package Geometry/Pastemask Bottom")
		(5 "F.SilkS" user "Ref Des/Silkscreen Top")
		(7 "B.SilkS" user "Ref Des/Silkscreen Bottom")
		(1 "F.Mask" user "Board Geometry/Soldermask Top")
		(3 "B.Mask" user "Board Geometry/Soldermask Bottom")
		(17 "Dwgs.User" user "User.Drawings")
		(19 "Cmts.User" user "User.Comments")
		(21 "Eco1.User" user "User.Eco1")
		(23 "Eco2.User" user "User.Eco2")
		(25 "Edge.Cuts" user "Board Geometry/Outline")
		(27 "Margin" user)
		(31 "F.CrtYd" user "Package Geometry/Place Bound Top")
		(29 "B.CrtYd" user "Package Geometry/Place Bound Bottom")
		(35 "F.Fab" user "Ref Des/Assembly Top")
		(33 "B.Fab" user "Ref Des/Assembly Bottom")
	)
	(footprint ""
		(layer "B.Cu")
		(at 490.57433 -298.306998 -90)
		(property "Reference" "X12"
			(at 2.985008 3.602736 270)
			(unlocked yes)
			(layer "B.SilkS")
			(effects
				(font
					(size 0.7874 0.5842)
					(thickness 0.1524)
				)
				(justify left mirror)
			)
		)
		(property "Value" ""
			(at 0 0 90)
			(layer "B.Fab")
			(effects
				(font
					(size 1.27 1.27)
				)
				(justify mirror)
			)
		)
		(property "User Part Number" "N_A"
			(at -1.30175 1.27 180)
			(unlocked yes)
			(layer "Cmts.User")
			(hide yes)
			(effects
				(font
					(size 0.635 0.4064)
					(thickness 0.1524)
				)
				(justify mirror)
			)
		)
		(property "Device Type" "TP_TDR_4P_FTS_TH-TP_TDR_4P_DIP,EMPTY,TP15"
			(at -1.30175 1.27 180)
			(unlocked yes)
			(layer "B.Fab")
			(hide yes)
			(effects
				(font
					(size 0.635 0.4064)
					(thickness 0.1524)
				)
				(justify mirror)
			)
		)
		(duplicate_pad_numbers_are_jumpers no)
		(fp_line
			(start -2.54 3.81)
			(end -2.54 3.6703)
			(stroke
				(width 0.1524)
				(type default)
			)
			(layer "B.SilkS")
		)
		(fp_line
			(start 0 3.81)
			(end -2.54 3.81)
			(stroke
				(width 0.1524)
				(type default)
			)
			(layer "B.SilkS")
		)
		(fp_line
			(start 0 3.175)
			(end 0 3.81)
			(stroke
				(width 0.1524)
				(type default)
			)
			(layer "B.SilkS")
		)
		(fp_line
			(start -2.54 1.4097)
			(end -2.54 1.1303)
			(stroke
				(width 0.1524)
				(type default)
			)
			(layer "B.SilkS")
		)
		(fp_line
			(start 0 0.635)
			(end 0 1.905)
			(stroke
				(width 0.1524)
				(type default)
			)
			(layer "B.SilkS")
		)
		(fp_line
			(start -2.54 -1.1303)
			(end -2.54 -1.27)
			(stroke
				(width 0.1524)
				(type default)
			)
			(layer "B.SilkS")
		)
		(fp_line
			(start -2.54 -1.27)
			(end 0 -1.27)
			(stroke
				(width 0.1524)
				(type default)
			)
			(layer "B.SilkS")
		)
		(fp_line
			(start 0 -1.27)
			(end 0 -0.635)
			(stroke
				(width 0.1524)
				(type default)
			)
			(layer "B.SilkS")
		)
		(fp_poly
			(pts
				(xy 2.285746 -0.762) (xy 2.285746 0.762) (xy 0.761746 0)
			)
			(stroke
				(width 0)
				(type default)
			)
			(fill yes)
			(layer "B.SilkS")
		)
		(fp_line
			(start -2.54 3.81)
			(end -2.54 -1.27)
			(stroke
				(width 0.1)
				(type default)
			)
			(layer "B.Fab")
		)
		(fp_line
			(start 0 3.81)
			(end -2.54 3.81)
			(stroke
				(width 0.1)
				(type default)
			)
			(layer "B.Fab")
		)
		(fp_line
			(start -2.54 -1.27)
			(end 0 -1.27)
			(stroke
				(width 0.1)
				(type default)
			)
			(layer "B.Fab")
		)
		(fp_line
			(start 0 -1.27)
			(end 0 3.81)
			(stroke
				(width 0.1)
				(type default)
			)
			(layer "B.Fab")
		)
		(fp_poly
			(pts
				(xy 0.761746 0) (xy 2.285746 -0.762) (xy 2.285746 0.762)
			)
			(stroke
				(width 0)
				(type default)
			)
			(fill yes)
			(layer "B.Fab")
		)
		(pad "1" thru_hole circle
			(at 0 0 90)
			(size 1.0033 1.0033)
			(drill 0.249936)
			(layers "*.Cu" "*.Mask")
			(remove_unused_layers no)
			(net "TDR_DIFF_80_BOT_DN")
			(clearance 0.10795)
			(padstack
				(mode front_inner_back)
				(layer "Inner"
					(shape circle)
					(size 0.8001 0.8001)
					(clearance 0.1524)
				)
				(layer "B.Cu"
					(shape circle)
					(size 1.0033 1.0033)
					(thermal_gap 0.10795)
					(clearance 0.10795)
				)
			)
		)
		(pad "2" thru_hole circle
			(at -2.54 0 90)
			(size 1.9939 1.9939)
			(drill 0.249936)
			(layers "*.Cu" "*.Mask")
			(remove_unused_layers no)
			(net "T1_GND")
			(clearance 0.10795)
			(padstack
				(mode front_inner_back)
				(layer "Inner"
					(shape circle)
					(size 0.8001 0.8001)
					(clearance 0.1524)
				)
				(layer "B.Cu"
					(shape circle)
					(size 1.9939 1.9939)
					(thermal_gap 0.10795)
					(clearance 0.10795)
				)
			)
		)
		(pad "3" thru_hole circle
			(at -2.54 2.54 90)
			(size 1.9939 1.9939)
			(drill 0.249936)
			(layers "*.Cu" "*.Mask")
			(remove_unused_layers no)
			(net "T1_GND")
			(clearance 0.10795)
			(padstack
				(mode front_inner_back)
				(layer "Inner"
					(shape circle)
					(size 0.8001 0.8001)
					(clearance 0.1524)
				)
				(layer "B.Cu"
					(shape circle)
					(size 1.9939 1.9939)
					(thermal_gap 0.10795)
					(clearance 0.10795)
				)
			)
		)
		(pad "4" thru_hole circle
			(at 0 2.54 90)
			(size 1.0033 1.0033)
			(drill 0.249936)
			(layers "*.Cu" "*.Mask")
			(remove_unused_layers no)
			(net "TDR_DIFF_80_BOT_DP")
			(clearance 0.10795)
			(padstack
				(mode front_inner_back)
				(layer "Inner"
					(shape circle)
					(size 0.8001 0.8001)
					(clearance 0.1524)
				)
				(layer "B.Cu"
					(shape circle)
					(size 1.0033 1.0033)
					(thermal_gap 0.10795)
					(clearance 0.10795)
				)
			)
		)
	)
	(footprint ""
		(layer "B.Cu")
		(at 113.841022 -26.03246)
		(property "Reference" "C6106"
			(at 0 0 0)
			(layer "B.SilkS")
			(hide yes)
			(effects
				(font
					(size 1.27 1.27)
				)
				(justify mirror)
			)
		)
		(property "Value" ""
			(at 0 0 0)
			(layer "B.Fab")
			(effects
				(font
					(size 1.27 1.27)
				)
				(justify mirror)
			)
		)
		(duplicate_pad_numbers_are_jumpers no)
		(fp_line
			(start -0.7874 -0.4064)
			(end -0.7874 0.4064)
			(stroke
				(width 0.1524)
				(type default)
			)
			(layer "B.SilkS")
		)
		(fp_line
			(start -0.7874 0.4064)
			(end 0.7874 0.4064)
			(stroke
				(width 0.1524)
				(type default)
			)
			(layer "B.SilkS")
		)
		(fp_line
			(start 0.7874 -0.4064)
			(end -0.7874 -0.4064)
			(stroke
				(width 0.1524)
				(type default)
			)
			(layer "B.SilkS")
		)
		(fp_line
			(start 0.7874 0.4064)
			(end 0.7874 -0.4064)
			(stroke
				(width 0.1524)
				(type default)
			)
			(layer "B.SilkS")
		)
		(fp_line
			(start -0.67945 -0.3048)
			(end -0.67945 0.3048)
			(stroke
				(width 0.1)
				(type default)
			)
			(layer "B.Fab")
		)
		(fp_line
			(start -0.67945 0.3048)
			(end -0.120396 0.3048)
			(stroke
				(width 0.1)
				(type default)
			)
			(layer "B.Fab")
		)
		(fp_line
			(start -0.12065 -0.3048)
			(end -0.67945 -0.3048)
			(stroke
				(width 0.1)
				(type default)
			)
			(layer "B.Fab")
		)
		(fp_line
			(start -0.12065 -0.2794)
			(end -0.12065 -0.3048)
			(stroke
				(width 0.1)
				(type default)
			)
			(layer "B.Fab")
		)
		(fp_line
			(start -0.120396 0.2794)
			(end 0.12065 0.2794)
			(stroke
				(width 0.1)
				(type default)
			)
			(layer "B.Fab")
		)
		(fp_line
			(start -0.120396 0.3048)
			(end -0.120396 0.2794)
			(stroke
				(width 0.1)
				(type default)
			)
			(layer "B.Fab")
		)
		(fp_line
			(start 0.12065 -0.305054)
			(end 0.12065 -0.2794)
			(stroke
				(width 0.1)
				(type default)
			)
			(layer "B.Fab")
		)
		(fp_line
			(start 0.12065 -0.2794)
			(end -0.12065 -0.2794)
			(stroke
				(width 0.1)
				(type default)
			)
			(layer "B.Fab")
		)
		(fp_line
			(start 0.12065 0.2794)
			(end 0.12065 0.3048)
			(stroke
				(width 0.1)
				(type default)
			)
			(layer "B.Fab")
		)
		(fp_line
			(start 0.12065 0.3048)
			(end 0.67945 0.3048)
			(stroke
				(width 0.1)
				(type default)
			)
			(layer "B.Fab")
		)
		(fp_line
			(start 0.67945 -0.305054)
			(end 0.12065 -0.305054)
			(stroke
				(width 0.1)
				(type default)
			)
			(layer "B.Fab")
		)
		(fp_line
			(start 0.67945 0.3048)
			(end 0.67945 -0.305054)
			(stroke
				(width 0.1)
				(type default)
			)
			(layer "B.Fab")
		)
		(pad "1" smd circle
			(at 0.40005 0 180)
			(size 0 0)
			(layers "B.Cu" "B.Mask" "B.Paste")
			(net "P1V2_CPU0_USB2_DVDD12")
		)
		(pad "2" smd circle
			(at -0.40005 0 180)
			(size 0 0)
			(layers "B.Cu" "B.Mask" "B.Paste")
			(net "GND")
		)
	)
	(footprint ""
		(layer "B.Cu")
		(at 376.33656 -180.078634 90)
		(property "Reference" "PR325"
			(at 0 0 90)
			(layer "B.SilkS")
			(hide yes)
			(effects
				(font
					(size 1.27 1.27)
				)
				(justify mirror)
			)
		)
		(property "Value" ""
			(at 0 0 90)
			(layer "B.Fab")
			(effects
				(font
					(size 1.27 1.27)
				)
				(justify mirror)
			)
		)
		(duplicate_pad_numbers_are_jumpers no)
		(fp_line
			(start 0.7874 -0.4064)
			(end -0.7874 -0.4064)
			(stroke
				(width 0.1524)
				(type default)
			)
			(layer "B.SilkS")
		)
		(fp_line
			(start -0.7874 -0.4064)
			(end -0.7874 0.4064)
			(stroke
				(width 0.1524)
				(type default)
			)
			(layer "B.SilkS")
		)
		(fp_line
			(start 0.7874 0.4064)
			(end 0.7874 -0.4064)
			(stroke
				(width 0.1524)
				(type default)
			)
			(layer "B.SilkS")
		)
		(fp_line
			(start -0.7874 0.4064)
			(end 0.7874 0.4064)
			(stroke
				(width 0.1524)
				(type default)
			)
			(layer "B.SilkS")
		)
		(fp_line
			(start 0.67945 -0.305054)
			(end 0.12065 -0.305054)
			(stroke
				(width 0.1)
				(type default)
			)
			(layer "B.Fab")
		)
		(fp_line
			(start 0.12065 -0.305054)
			(end 0.12065 -0.2794)
			(stroke
				(width 0.1)
				(type default)
			)
			(layer "B.Fab")
		)
		(fp_line
			(start -0.12065 -0.3048)
			(end -0.67945 -0.3048)
			(stroke
				(width 0.1)
				(type default)
			)
			(layer "B.Fab")
		)
		(fp_line
			(start -0.67945 -0.3048)
			(end -0.67945 0.3048)
			(stroke
				(width 0.1)
				(type default)
			)
			(layer "B.Fab")
		)
		(fp_line
			(start 0.12065 -0.2794)
			(end -0.12065 -0.2794)
			(stroke
				(width 0.1)
				(type default)
			)
			(layer "B.Fab")
		)
		(fp_line
			(start -0.12065 -0.2794)
			(end -0.12065 -0.3048)
			(stroke
				(width 0.1)
				(type default)
			)
			(layer "B.Fab")
		)
		(fp_line
			(start 0.12065 0.2794)
			(end 0.12065 0.3048)
			(stroke
				(width 0.1)
				(type default)
			)
			(layer "B.Fab")
		)
		(fp_line
			(start -0.120396 0.2794)
			(end 0.12065 0.2794)
			(stroke
				(width 0.1)
				(type default)
			)
			(layer "B.Fab")
		)
		(fp_line
			(start 0.67945 0.3048)
			(end 0.67945 -0.305054)
			(stroke
				(width 0.1)
				(type default)
			)
			(layer "B.Fab")
		)
		(fp_line
			(start 0.12065 0.3048)
			(end 0.67945 0.3048)
			(stroke
				(width 0.1)
				(type default)
			)
			(layer "B.Fab")
		)
		(fp_line
			(start -0.120396 0.3048)
			(end -0.120396 0.2794)
			(stroke
				(width 0.1)
				(type default)
			)
			(layer "B.Fab")
		)
		(fp_line
			(start -0.67945 0.3048)
			(end -0.120396 0.3048)
			(stroke
				(width 0.1)
				(type default)
			)
			(layer "B.Fab")
		)
		(pad "1" smd circle
			(at 0.40005 0 270)
			(size 0 0)
			(layers "B.Cu" "B.Mask" "B.Paste")
			(net "PVDDCR_CPU0_P0_VOS2")
		)
		(pad "2" smd circle
			(at -0.40005 0 270)
			(size 0 0)
			(layers "B.Cu" "B.Mask" "B.Paste")
			(net "PVDDCR_CPU0_P0")
		)
	)
	(footprint ""
		(layer "B.Cu")
		(at 112.521238 -388.296912)
		(property "Reference" "C498"
			(at 0 0 0)
			(layer "B.SilkS")
			(hide yes)
			(effects
				(font
					(size 1.27 1.27)
				)
				(justify mirror)
			)
		)
		(property "Value" ""
			(at 0 0 0)
			(layer "B.Fab")
			(effects
				(font
					(size 1.27 1.27)
				)
				(justify mirror)
			)
		)
		(duplicate_pad_numbers_are_jumpers no)
		(fp_line
			(start -0.299974 -0.150114)
			(end -0.299974 0.150114)
			(stroke
				(width 0.1)
				(type default)
			)
			(layer "B.Fab")
		)
		(fp_line
			(start -0.299974 0.150114)
			(end 0.299974 0.150114)
			(stroke
				(width 0.1)
				(type default)
			)
			(layer "B.Fab")
		)
		(fp_line
			(start 0.299974 -0.150114)
			(end -0.299974 -0.150114)
			(stroke
				(width 0.1)
				(type default)
			)
			(layer "B.Fab")
		)
		(fp_line
			(start 0.299974 0.150114)
			(end 0.299974 -0.150114)
			(stroke
				(width 0.1)
				(type default)
			)
			(layer "B.Fab")
		)
		(pad "1" smd rect
			(at 0.2667 0 180)
			(size 0.3048 0.381)
			(layers "B.Cu" "B.Mask" "B.Paste")
			(net "P0V9_CPU1_RT3_2A")
		)
		(pad "2" smd rect
			(at -0.2667 0 180)
			(size 0.3048 0.381)
			(layers "B.Cu" "B.Mask" "B.Paste")
			(net "GND")
		)
	)
	(footprint ""
		(layer "B.Cu")
		(at 162.746182 -388.011162 -90)
		(property "Reference" "C400"
			(at 0 0 90)
			(layer "B.SilkS")
			(hide yes)
			(effects
				(font
					(size 1.27 1.27)
				)
				(justify mirror)
			)
		)
		(property "Value" ""
			(at 0 0 90)
			(layer "B.Fab")
			(effects
				(font
					(size 1.27 1.27)
				)
				(justify mirror)
			)
		)
		(duplicate_pad_numbers_are_jumpers no)
		(fp_line
			(start -0.299974 0.150114)
			(end 0.299974 0.150114)
			(stroke
				(width 0.1)
				(type default)
			)
			(layer "B.Fab")
		)
		(fp_line
			(start 0.299974 0.150114)
			(end 0.299974 -0.150114)
			(stroke
				(width 0.1)
				(type default)
			)
			(layer "B.Fab")
		)
		(fp_line
			(start -0.299974 -0.150114)
			(end -0.299974 0.150114)
			(stroke
				(width 0.1)
				(type default)
			)
			(layer "B.Fab")
		)
		(fp_line
			(start 0.299974 -0.150114)
			(end -0.299974 -0.150114)
			(stroke
				(width 0.1)
				(type default)
			)
			(layer "B.Fab")
		)
		(pad "1" smd rect
			(at 0.2667 0 90)
			(size 0.3048 0.381)
			(layers "B.Cu" "B.Mask" "B.Paste")
			(net "P0V9_CPU1_RT2_2A")
		)
		(pad "2" smd rect
			(at -0.2667 0 90)
			(size 0.3048 0.381)
			(layers "B.Cu" "B.Mask" "B.Paste")
			(net "GND")
		)
	)
	(footprint ""
		(layer "B.Cu")
		(at 361.046014 -258.795012 180)
		(property "Reference" "C3926"
			(at 0 0 0)
			(layer "B.SilkS")
			(hide yes)
			(effects
				(font
					(size 1.27 1.27)
				)
				(justify mirror)
			)
		)
		(property "Value" ""
			(at 0 0 0)
			(layer "B.Fab")
			(effects
				(font
					(size 1.27 1.27)
				)
				(justify mirror)
			)
		)
		(duplicate_pad_numbers_are_jumpers no)
		(fp_line
			(start 0.7874 0.4064)
			(end 0.7874 -0.4064)
			(stroke
				(width 0.1524)
				(type default)
			)
			(layer "B.SilkS")
		)
		(fp_line
			(start 0.7874 -0.4064)
			(end -0.7874 -0.4064)
			(stroke
				(width 0.1524)
				(type default)
			)
			(layer "B.SilkS")
		)
		(fp_line
			(start -0.7874 0.4064)
			(end 0.7874 0.4064)
			(stroke
				(width 0.1524)
				(type default)
			)
			(layer "B.SilkS")
		)
		(fp_line
			(start -0.7874 -0.4064)
			(end -0.7874 0.4064)
			(stroke
				(width 0.1524)
				(type default)
			)
			(layer "B.SilkS")
		)
		(fp_line
			(start 0.67945 0.3048)
			(end 0.67945 -0.305054)
			(stroke
				(width 0.1)
				(type default)
			)
			(layer "B.Fab")
		)
		(fp_line
			(start 0.67945 -0.305054)
			(end 0.12065 -0.305054)
			(stroke
				(width 0.1)
				(type default)
			)
			(layer "B.Fab")
		)
		(fp_line
			(start 0.12065 0.3048)
			(end 0.67945 0.3048)
			(stroke
				(width 0.1)
				(type default)
			)
			(layer "B.Fab")
		)
		(fp_line
			(start 0.12065 0.2794)
			(end 0.12065 0.3048)
			(stroke
				(width 0.1)
				(type default)
			)
			(layer "B.Fab")
		)
		(fp_line
			(start 0.12065 -0.2794)
			(end -0.12065 -0.2794)
			(stroke
				(width 0.1)
				(type default)
			)
			(layer "B.Fab")
		)
		(fp_line
			(start 0.12065 -0.305054)
			(end 0.12065 -0.2794)
			(stroke
				(width 0.1)
				(type default)
			)
			(layer "B.Fab")
		)
		(fp_line
			(start -0.120396 0.3048)
			(end -0.120396 0.2794)
			(stroke
				(width 0.1)
				(type default)
			)
			(layer "B.Fab")
		)
		(fp_line
			(start -0.120396 0.2794)
			(end 0.12065 0.2794)
			(stroke
				(width 0.1)
				(type default)
			)
			(layer "B.Fab")
		)
		(fp_line
			(start -0.12065 -0.2794)
			(end -0.12065 -0.3048)
			(stroke
				(width 0.1)
				(type default)
			)
			(layer "B.Fab")
		)
		(fp_line
			(start -0.12065 -0.3048)
			(end -0.67945 -0.3048)
			(stroke
				(width 0.1)
				(type default)
			)
			(layer "B.Fab")
		)
		(fp_line
			(start -0.67945 0.3048)
			(end -0.120396 0.3048)
			(stroke
				(width 0.1)
				(type default)
			)
			(layer "B.Fab")
		)
		(fp_line
			(start -0.67945 -0.3048)
			(end -0.67945 0.3048)
			(stroke
				(width 0.1)
				(type default)
			)
			(layer "B.Fab")
		)
		(pad "1" smd circle
			(at 0.40005 0)
			(size 0 0)
			(layers "B.Cu" "B.Mask" "B.Paste")
			(net "PVDDCR_SOC_P0")
		)
		(pad "2" smd circle
			(at -0.40005 0)
			(size 0 0)
			(layers "B.Cu" "B.Mask" "B.Paste")
			(net "GND")
		)
	)
	(footprint ""
		(layer "B.Cu")
		(at 232.537 -335.153 90)
		(property "Reference" "R6768"
			(at 0 0 90)
			(layer "B.SilkS")
			(hide yes)
			(effects
				(font
					(size 1.27 1.27)
				)
				(justify mirror)
			)
		)
		(property "Value" ""
			(at 0 0 90)
			(layer "B.Fab")
			(effects
				(font
					(size 1.27 1.27)
				)
				(justify mirror)
			)
		)
		(duplicate_pad_numbers_are_jumpers no)
		(fp_line
			(start 0.32512 -0.175006)
			(end -0.32512 -0.175006)
			(stroke
				(width 0.1)
				(type default)
			)
			(layer "B.Fab")
		)
		(fp_line
			(start -0.32512 -0.175006)
			(end -0.32512 0.175006)
			(stroke
				(width 0.1)
				(type default)
			)
			(layer "B.Fab")
		)
		(fp_line
			(start 0.32512 0.175006)
			(end 0.32512 -0.175006)
			(stroke
				(width 0.1)
				(type default)
			)
			(layer "B.Fab")
		)
		(fp_line
			(start -0.32512 0.175006)
			(end 0.32512 0.175006)
			(stroke
				(width 0.1)
				(type default)
			)
			(layer "B.Fab")
		)
		(pad "1" smd rect
			(at 0.2667 0 270)
			(size 0.3048 0.381)
			(layers "B.Cu" "B.Mask" "B.Paste")
			(net "P1V8_CPU0_RT_1D")
		)
		(pad "2" smd rect
			(at -0.2667 0 90)
			(size 0.3048 0.381)
			(layers "B.Cu" "B.Mask" "B.Paste")
			(net "SMB_RT_CPU0_P2_R_SDA")
		)
	)
)
